# TIMECARD (Time Appliance Project (Time Card)) — schematic netlist excerpt (pin names and nets, part order shuffled) for the footprints in the layout excerpt that follows; sources: Cadence DE-HDL packaged netlist, KiCad conversion of R4006-B0001-02_R01.brd

DS4  OPTICAL  pkg SMC_DS_063X031_V4  page 26 : A = UNNAMED_14_OPTICAL_I137_A ; C = LED_DATOUT0
C306  CAPACITOR  0.1UF 25V 10%  pkg SMC_0402R_H022  page 17 : \1\ = SG ; \2\ = XP3R3V_FPGA

(kicad_pcb
	(version 20260206)
	(generator "pcbnew")
	(generator_version "10.0")
	(general
		(thickness 1.6)
		(legacy_teardrops no)
	)
	(paper "A4")
	(title_block
		(title "timecard-production-celestica-r4006 — R4006-B0001-02_R01.brd")
		(comment 1 "Time Appliance Project (Time Card) / footprints 397-398 of 1113")
	)
	(layers
		(0 "F.Cu" signal "TOP")
		(4 "In1.Cu" signal "L02_GND1")
		(6 "In2.Cu" signal "L03_SIG1")
		(8 "In3.Cu" signal "L04_GND2")
		(10 "In4.Cu" signal "L05_VCC1")
		(12 "In5.Cu" signal "L06_VCC2")
		(14 "In6.Cu" signal "L07_GND3")
		(16 "In7.Cu" signal "L08_SIG2")
		(18 "In8.Cu" signal "L09_GND4")
		(2 "B.Cu" signal "BOTTOM")
		(9 "F.Adhes" user "F.Adhesive")
		(11 "B.Adhes" user "B.Adhesive")
		(13 "F.Paste" user "Package Geometry/Pastemask Top")
		(15 "B.Paste" user "Package Geometry/Pastemask Bottom")
		(5 "F.SilkS" user "Ref Des/Silkscreen Top")
		(7 "B.SilkS" user "Ref Des/Silkscreen Bottom")
		(1 "F.Mask" user "Board Geometry/Soldermask Top")
		(3 "B.Mask" user "Board Geometry/Soldermask Bottom")
		(17 "Dwgs.User" user "User.Drawings")
		(19 "Cmts.User" user "User.Comments")
		(21 "Eco1.User" user "User.Eco1")
		(23 "Eco2.User" user "User.Eco2")
		(25 "Edge.Cuts" user "Board Geometry/Outline")
		(27 "Margin" user)
		(31 "F.CrtYd" user "Package Geometry/Place Bound Top")
		(29 "B.CrtYd" user "Package Geometry/Place Bound Bottom")
		(35 "F.Fab" user "Ref Des/Assembly Top")
		(33 "B.Fab" user "Ref Des/Assembly Bottom")
	)
	(footprint ""
		(layer "F.Cu")
		(at 147.049998 -107.849924 -90)
		(property "Reference" "DS4"
			(at -0.862076 -1.706372 90)
			(unlocked yes)
			(layer "F.SilkS")
			(effects
				(font
					(size 0.7874 0.5842)
					(thickness 0.1524)
				)
			)
		)
		(property "Value" ""
			(at 0 0 270)
			(layer "F.Fab")
			(effects
				(font
					(size 1.27 1.27)
				)
			)
		)
		(property "User Part Number" "PARTNUM*"
			(at 0.1778 2.422881 270)
			(unlocked yes)
			(layer "Cmts.User")
			(hide yes)
			(effects
				(font
					(size 0.786892 0.583946)
					(thickness 0.000001)
				)
			)
		)
		(property "Device Type" "OPTICAL-G170-10143-01"
			(at 0.1778 1.483081 270)
			(unlocked yes)
			(layer "F.Fab")
			(hide yes)
			(effects
				(font
					(size 0.786892 0.583946)
					(thickness 0.000001)
				)
			)
		)
		(duplicate_pad_numbers_are_jumpers no)
		(fp_line
			(start -1.3208 1.0922)
			(end -2.5908 1.0922)
			(stroke
				(width 0.1)
				(type default)
			)
			(layer "F.SilkS")
		)
		(fp_line
			(start -1.397508 0.704088)
			(end -1.397508 -0.704088)
			(stroke
				(width 0.1)
				(type default)
			)
			(layer "F.SilkS")
		)
		(fp_line
			(start 1.397508 0.704088)
			(end -1.397508 0.704088)
			(stroke
				(width 0.1)
				(type default)
			)
			(layer "F.SilkS")
		)
		(fp_line
			(start -1.9558 0.4572)
			(end -1.9558 1.7272)
			(stroke
				(width 0.1)
				(type default)
			)
			(layer "F.SilkS")
		)
		(fp_line
			(start -1.397508 -0.704088)
			(end 1.397508 -0.704088)
			(stroke
				(width 0.1)
				(type default)
			)
			(layer "F.SilkS")
		)
		(fp_line
			(start 1.397508 -0.704088)
			(end 1.397508 0.704088)
			(stroke
				(width 0.1)
				(type default)
			)
			(layer "F.SilkS")
		)
		(fp_rect
			(start 1.905508 0.704088)
			(end 1.397508 -0.704088)
			(stroke
				(width 0)
				(type default)
			)
			(fill yes)
			(layer "F.SilkS")
		)
		(fp_rect
			(start 1.905508 0.958088)
			(end -1.651508 -0.958088)
			(stroke
				(width 0)
				(type default)
			)
			(fill no)
			(layer "F.CrtYd")
		)
		(fp_line
			(start -1.4478 0.9652)
			(end -2.7178 0.9652)
			(stroke
				(width 0.1)
				(type default)
			)
			(layer "F.Fab")
		)
		(fp_line
			(start -0.850138 0.450088)
			(end 0.850138 0.450088)
			(stroke
				(width 0.1)
				(type default)
			)
			(layer "F.Fab")
		)
		(fp_line
			(start 0.850138 0.450088)
			(end 0.850138 -0.450088)
			(stroke
				(width 0.1)
				(type default)
			)
			(layer "F.Fab")
		)
		(fp_line
			(start -2.0828 0.3302)
			(end -2.0828 1.6002)
			(stroke
				(width 0.1)
				(type default)
			)
			(layer "F.Fab")
		)
		(fp_line
			(start -0.850138 -0.450088)
			(end -0.850138 0.450088)
			(stroke
				(width 0.1)
				(type default)
			)
			(layer "F.Fab")
		)
		(fp_line
			(start 0.850138 -0.450088)
			(end -0.850138 -0.450088)
			(stroke
				(width 0.1)
				(type default)
			)
			(layer "F.Fab")
		)
		(fp_rect
			(start 0.850138 0.450088)
			(end 0.342138 -0.450088)
			(stroke
				(width 0)
				(type default)
			)
			(fill yes)
			(layer "F.Fab")
		)
		(fp_text user "A"
			(at -1.846326 -0.778002 0)
			(unlocked yes)
			(layer "F.SilkS")
			(effects
				(font
					(size 0.635 0.4064)
					(thickness 0.1524)
				)
			)
		)
		(fp_text user "C"
			(at 1.201674 -1.540002 0)
			(unlocked yes)
			(layer "F.SilkS")
			(effects
				(font
					(size 0.635 0.4064)
					(thickness 0.1524)
				)
			)
		)
		(fp_text user "A"
			(at -1.700276 0.032004 0)
			(unlocked yes)
			(layer "F.Fab")
			(effects
				(font
					(size 0.7874 0.5842)
					(thickness 0.1524)
				)
			)
		)
		(fp_text user "C"
			(at 0.828294 -1.159002 0)
			(unlocked yes)
			(layer "F.Fab")
			(effects
				(font
					(size 0.7874 0.5842)
					(thickness 0.1524)
				)
			)
		)
		(pad "A" smd rect
			(at -0.749808 0 270)
			(size 0.7874 0.7874)
			(layers "F.Cu" "F.Mask" "F.Paste")
			(net "UNNAMED_14_OPTICAL_I137_A")
		)
		(pad "C" smd rect
			(at 0.749808 0 270)
			(size 0.7874 0.7874)
			(layers "F.Cu" "F.Mask" "F.Paste")
			(net "LED_DATOUT0")
		)
	)
	(footprint ""
		(layer "F.Cu")
		(at 56.3372 -74.9808 90)
		(property "Reference" "C306"
			(at -0.5588 4.15417 90)
			(unlocked yes)
			(layer "F.SilkS")
			(effects
				(font
					(size 0.7874 0.5842)
					(thickness 0.1524)
				)
			)
		)
		(property "Value" "VAL*"
			(at 0.0762 2.067306 90)
			(unlocked yes)
			(layer "F.Fab")
			(hide yes)
			(effects
				(font
					(size 0.7874 0.5842)
					(thickness 0.1524)
				)
			)
		)
		(property "Tolerance" "TOL*"
			(at 0.0762 3.032506 90)
			(unlocked yes)
			(layer "Cmts.User")
			(hide yes)
			(effects
				(font
					(size 0.7874 0.5842)
					(thickness 0.1524)
				)
			)
		)
		(property "User Part Number" "PARTNUM*"
			(at 0.1016 4.023106 90)
			(unlocked yes)
			(layer "Cmts.User")
			(hide yes)
			(effects
				(font
					(size 0.7874 0.5842)
					(thickness 0.1524)
				)
			)
		)
		(property "Device Type" "CAPACITOR-G105-0B104-EK,0.1UF,A"
			(at 0.0508 1.127506 90)
			(unlocked yes)
			(layer "F.Fab")
			(hide yes)
			(effects
				(font
					(size 0.7874 0.5842)
					(thickness 0.1524)
				)
			)
		)
		(duplicate_pad_numbers_are_jumpers no)
		(fp_line
			(start 1.143 -0.5588)
			(end -1.143 -0.5588)
			(stroke
				(width 0.1)
				(type default)
			)
			(layer "F.SilkS")
		)
		(fp_line
			(start -1.143 -0.5588)
			(end -1.143 0.5588)
			(stroke
				(width 0.1)
				(type default)
			)
			(layer "F.SilkS")
		)
		(fp_line
			(start 1.143 0.5588)
			(end 1.143 -0.5588)
			(stroke
				(width 0.1)
				(type default)
			)
			(layer "F.SilkS")
		)
		(fp_line
			(start -1.143 0.5588)
			(end 1.143 0.5588)
			(stroke
				(width 0.1)
				(type default)
			)
			(layer "F.SilkS")
		)
		(fp_rect
			(start -1.143 0.5588)
			(end 1.143 -0.5588)
			(stroke
				(width 0)
				(type default)
			)
			(fill no)
			(layer "F.CrtYd")
		)
		(fp_line
			(start 0.508 -0.3048)
			(end -0.508 -0.3048)
			(stroke
				(width 0.1)
				(type default)
			)
			(layer "F.Fab")
		)
		(fp_line
			(start -0.508 -0.3048)
			(end -0.508 0.3048)
			(stroke
				(width 0.1)
				(type default)
			)
			(layer "F.Fab")
		)
		(fp_line
			(start 0.508 0.3048)
			(end 0.508 -0.3048)
			(stroke
				(width 0.1)
				(type default)
			)
			(layer "F.Fab")
		)
		(fp_line
			(start -0.508 0.3048)
			(end 0.508 0.3048)
			(stroke
				(width 0.1)
				(type default)
			)
			(layer "F.Fab")
		)
		(pad "1" smd rect
			(at -0.5334 0 90)
			(size 0.7112 0.6096)
			(layers "F.Cu" "F.Mask" "F.Paste")
			(net "SG")
		)
		(pad "2" smd rect
			(at 0.5334 0 90)
			(size 0.7112 0.6096)
			(layers "F.Cu" "F.Mask" "F.Paste")
			(net "XP3R3V_FPGA")
		)
		(zone
			(layer "F.Cu")
			(hatch none 0.5)
			(connect_pads
				(clearance 0)
			)
			(min_thickness 0.25)
			(keepout
				(tracks allowed)
				(vias not_allowed)
				(pads allowed)
				(copperpour not_allowed)
				(footprints allowed)
			)
			(placement
				(enabled no)
				(sheetname "")
			)
			(fill
				(thermal_gap 0.5)
				(thermal_bridge_width 0.5)
				(island_removal_mode 0)
			)
			(polygon
				(pts
					(xy 56.642 -74.9046) (xy 56.642 -75.057) (xy 56.0324 -75.057) (xy 56.0324 -74.9046)
				)
			)
		)
		(zone
			(layer "F.Cu")
			(hatch none 0.5)
			(connect_pads
				(clearance 0)
			)
			(min_thickness 0.25)
			(keepout
				(tracks not_allowed)
				(vias allowed)
				(pads allowed)
				(copperpour not_allowed)
				(footprints allowed)
			)
			(placement
				(enabled no)
				(sheetname "")
			)
			(fill
				(thermal_gap 0.5)
				(thermal_bridge_width 0.5)
				(island_removal_mode 0)
			)
			(polygon
				(pts
					(xy 56.642 -74.9046) (xy 56.642 -75.057) (xy 56.0324 -75.057) (xy 56.0324 -74.9046)
				)
			)
		)
	)
)
